# T6G (Grand Teton) — schematic netlist excerpt (pin names and nets, part order shuffled) for the footprints in the layout excerpt that follows; sources: Cadence DE-HDL packaged netlist, KiCad conversion of 04192023_DAF0TMB3IC0_F0TG_MB_C_brd_V02_OCP.brd

C2417  Q_CAP  22UF 4V 20% X6S  pkg C0402  page 74 : A = PVDDCR_SOC_P1 ; B = GND
C2303  Q_CAP  22UF 4V 20% X6S  pkg C0402  page 73 : A = PVDDCR_CPU0_P1 ; B = GND
R6779  Q_RES  33.2 1% CHIP  pkg 0201LF  page 184 : A = SMB_MUX_RT_SDA ; B = SMB_MUX_RT_R1_SDA

(kicad_pcb
	(version 20260206)
	(generator "pcbnew")
	(generator_version "10.0")
	(general
		(thickness 1.6)
		(legacy_teardrops no)
	)
	(paper "A4")
	(title_block
		(title "04192023_DAF0TMB3IC0_F0TG_MB_C_brd_V02_OCP.brd")
		(comment 1 "Grand Teton / footprints 5482-5484 of 8354")
	)
	(layers
		(0 "F.Cu" signal "TOP")
		(4 "In1.Cu" signal "GND")
		(6 "In2.Cu" signal "IN1")
		(8 "In3.Cu" signal "GND1")
		(10 "In4.Cu" signal "IN2")
		(12 "In5.Cu" signal "GND2")
		(14 "In6.Cu" signal "IN3")
		(16 "In7.Cu" signal "GND3")
		(18 "In8.Cu" signal "VCC")
		(20 "In9.Cu" signal "VCC1")
		(22 "In10.Cu" signal "GND4")
		(24 "In11.Cu" signal "IN4")
		(26 "In12.Cu" signal "GND5")
		(28 "In13.Cu" signal "IN5")
		(30 "In14.Cu" signal "GND6")
		(32 "In15.Cu" signal "IN6")
		(34 "In16.Cu" signal "GND7")
		(2 "B.Cu" signal "BOTTOM")
		(9 "F.Adhes" user "F.Adhesive")
		(11 "B.Adhes" user "B.Adhesive")
		(13 "F.Paste" user "Package Geometry/Pastemask Top")
		(15 "B.Paste" user "Package Geometry/Pastemask Bottom")
		(5 "F.SilkS" user "Ref Des/Silkscreen Top")
		(7 "B.SilkS" user "Ref Des/Silkscreen Bottom")
		(1 "F.Mask" user "Board Geometry/Soldermask Top")
		(3 "B.Mask" user "Board Geometry/Soldermask Bottom")
		(17 "Dwgs.User" user "User.Drawings")
		(19 "Cmts.User" user "User.Comments")
		(21 "Eco1.User" user "User.Eco1")
		(23 "Eco2.User" user "User.Eco2")
		(25 "Edge.Cuts" user "Board Geometry/Outline")
		(27 "Margin" user)
		(31 "F.CrtYd" user "Package Geometry/Place Bound Top")
		(29 "B.CrtYd" user "Package Geometry/Place Bound Bottom")
		(35 "F.Fab" user "Ref Des/Assembly Top")
		(33 "B.Fab" user "Ref Des/Assembly Bottom")
	)
	(footprint ""
		(layer "B.Cu")
		(at 230.886 -330.708 180)
		(property "Reference" "R6779"
			(at 0 0 0)
			(layer "B.SilkS")
			(hide yes)
			(effects
				(font
					(size 1.27 1.27)
				)
				(justify mirror)
			)
		)
		(property "Value" ""
			(at 0 0 0)
			(layer "B.Fab")
			(effects
				(font
					(size 1.27 1.27)
				)
				(justify mirror)
			)
		)
		(duplicate_pad_numbers_are_jumpers no)
		(fp_line
			(start 0.32512 0.175006)
			(end 0.32512 -0.175006)
			(stroke
				(width 0.1)
				(type default)
			)
			(layer "B.Fab")
		)
		(fp_line
			(start 0.32512 -0.175006)
			(end -0.32512 -0.175006)
			(stroke
				(width 0.1)
				(type default)
			)
			(layer "B.Fab")
		)
		(fp_line
			(start -0.32512 0.175006)
			(end 0.32512 0.175006)
			(stroke
				(width 0.1)
				(type default)
			)
			(layer "B.Fab")
		)
		(fp_line
			(start -0.32512 -0.175006)
			(end -0.32512 0.175006)
			(stroke
				(width 0.1)
				(type default)
			)
			(layer "B.Fab")
		)
		(pad "1" smd rect
			(at 0.2667 0)
			(size 0.3048 0.381)
			(layers "B.Cu" "B.Mask" "B.Paste")
			(net "SMB_MUX_RT_SDA")
		)
		(pad "2" smd rect
			(at -0.2667 0 180)
			(size 0.3048 0.381)
			(layers "B.Cu" "B.Mask" "B.Paste")
			(net "SMB_MUX_RT_R1_SDA")
		)
	)
	(footprint ""
		(layer "B.Cu")
		(at 108.625894 -256.012442 -90)
		(property "Reference" "C2417"
			(at 0 0 90)
			(layer "B.SilkS")
			(hide yes)
			(effects
				(font
					(size 1.27 1.27)
				)
				(justify mirror)
			)
		)
		(property "Value" ""
			(at 0 0 90)
			(layer "B.Fab")
			(effects
				(font
					(size 1.27 1.27)
				)
				(justify mirror)
			)
		)
		(duplicate_pad_numbers_are_jumpers no)
		(fp_line
			(start -0.7874 0.4064)
			(end 0.7874 0.4064)
			(stroke
				(width 0.1524)
				(type default)
			)
			(layer "B.SilkS")
		)
		(fp_line
			(start 0.7874 0.4064)
			(end 0.7874 -0.4064)
			(stroke
				(width 0.1524)
				(type default)
			)
			(layer "B.SilkS")
		)
		(fp_line
			(start -0.7874 -0.4064)
			(end -0.7874 0.4064)
			(stroke
				(width 0.1524)
				(type default)
			)
			(layer "B.SilkS")
		)
		(fp_line
			(start 0.7874 -0.4064)
			(end -0.7874 -0.4064)
			(stroke
				(width 0.1524)
				(type default)
			)
			(layer "B.SilkS")
		)
		(fp_line
			(start -0.67945 0.3048)
			(end -0.120396 0.3048)
			(stroke
				(width 0.1)
				(type default)
			)
			(layer "B.Fab")
		)
		(fp_line
			(start -0.120396 0.3048)
			(end -0.120396 0.2794)
			(stroke
				(width 0.1)
				(type default)
			)
			(layer "B.Fab")
		)
		(fp_line
			(start 0.12065 0.3048)
			(end 0.67945 0.3048)
			(stroke
				(width 0.1)
				(type default)
			)
			(layer "B.Fab")
		)
		(fp_line
			(start 0.67945 0.3048)
			(end 0.67945 -0.305054)
			(stroke
				(width 0.1)
				(type default)
			)
			(layer "B.Fab")
		)
		(fp_line
			(start -0.120396 0.2794)
			(end 0.12065 0.2794)
			(stroke
				(width 0.1)
				(type default)
			)
			(layer "B.Fab")
		)
		(fp_line
			(start 0.12065 0.2794)
			(end 0.12065 0.3048)
			(stroke
				(width 0.1)
				(type default)
			)
			(layer "B.Fab")
		)
		(fp_line
			(start -0.12065 -0.2794)
			(end -0.12065 -0.3048)
			(stroke
				(width 0.1)
				(type default)
			)
			(layer "B.Fab")
		)
		(fp_line
			(start 0.12065 -0.2794)
			(end -0.12065 -0.2794)
			(stroke
				(width 0.1)
				(type default)
			)
			(layer "B.Fab")
		)
		(fp_line
			(start -0.67945 -0.3048)
			(end -0.67945 0.3048)
			(stroke
				(width 0.1)
				(type default)
			)
			(layer "B.Fab")
		)
		(fp_line
			(start -0.12065 -0.3048)
			(end -0.67945 -0.3048)
			(stroke
				(width 0.1)
				(type default)
			)
			(layer "B.Fab")
		)
		(fp_line
			(start 0.12065 -0.305054)
			(end 0.12065 -0.2794)
			(stroke
				(width 0.1)
				(type default)
			)
			(layer "B.Fab")
		)
		(fp_line
			(start 0.67945 -0.305054)
			(end 0.12065 -0.305054)
			(stroke
				(width 0.1)
				(type default)
			)
			(layer "B.Fab")
		)
		(pad "1" smd circle
			(at 0.40005 0 90)
			(size 0 0)
			(layers "B.Cu" "B.Mask" "B.Paste")
			(net "PVDDCR_SOC_P1")
		)
		(pad "2" smd circle
			(at -0.40005 0 90)
			(size 0 0)
			(layers "B.Cu" "B.Mask" "B.Paste")
			(net "GND")
		)
	)
	(footprint ""
		(layer "B.Cu")
		(at 100.906834 -249.368564 180)
		(property "Reference" "C2303"
			(at 0 0 0)
			(layer "B.SilkS")
			(hide yes)
			(effects
				(font
					(size 1.27 1.27)
				)
				(justify mirror)
			)
		)
		(property "Value" ""
			(at 0 0 0)
			(layer "B.Fab")
			(effects
				(font
					(size 1.27 1.27)
				)
				(justify mirror)
			)
		)
		(duplicate_pad_numbers_are_jumpers no)
		(fp_line
			(start 0.7874 0.4064)
			(end 0.7874 -0.4064)
			(stroke
				(width 0.1524)
				(type default)
			)
			(layer "B.SilkS")
		)
		(fp_line
			(start 0.7874 -0.4064)
			(end -0.7874 -0.4064)
			(stroke
				(width 0.1524)
				(type default)
			)
			(layer "B.SilkS")
		)
		(fp_line
			(start -0.7874 0.4064)
			(end 0.7874 0.4064)
			(stroke
				(width 0.1524)
				(type default)
			)
			(layer "B.SilkS")
		)
		(fp_line
			(start -0.7874 -0.4064)
			(end -0.7874 0.4064)
			(stroke
				(width 0.1524)
				(type default)
			)
			(layer "B.SilkS")
		)
		(fp_line
			(start 0.67945 0.3048)
			(end 0.67945 -0.305054)
			(stroke
				(width 0.1)
				(type default)
			)
			(layer "B.Fab")
		)
		(fp_line
			(start 0.67945 -0.305054)
			(end 0.12065 -0.305054)
			(stroke
				(width 0.1)
				(type default)
			)
			(layer "B.Fab")
		)
		(fp_line
			(start 0.12065 0.3048)
			(end 0.67945 0.3048)
			(stroke
				(width 0.1)
				(type default)
			)
			(layer "B.Fab")
		)
		(fp_line
			(start 0.12065 0.2794)
			(end 0.12065 0.3048)
			(stroke
				(width 0.1)
				(type default)
			)
			(layer "B.Fab")
		)
		(fp_line
			(start 0.12065 -0.2794)
			(end -0.12065 -0.2794)
			(stroke
				(width 0.1)
				(type default)
			)
			(layer "B.Fab")
		)
		(fp_line
			(start 0.12065 -0.305054)
			(end 0.12065 -0.2794)
			(stroke
				(width 0.1)
				(type default)
			)
			(layer "B.Fab")
		)
		(fp_line
			(start -0.120396 0.3048)
			(end -0.120396 0.2794)
			(stroke
				(width 0.1)
				(type default)
			)
			(layer "B.Fab")
		)
		(fp_line
			(start -0.120396 0.2794)
			(end 0.12065 0.2794)
			(stroke
				(width 0.1)
				(type default)
			)
			(layer "B.Fab")
		)
		(fp_line
			(start -0.12065 -0.2794)
			(end -0.12065 -0.3048)
			(stroke
				(width 0.1)
				(type default)
			)
			(layer "B.Fab")
		)
		(fp_line
			(start -0.12065 -0.3048)
			(end -0.67945 -0.3048)
			(stroke
				(width 0.1)
				(type default)
			)
			(layer "B.Fab")
		)
		(fp_line
			(start -0.67945 0.3048)
			(end -0.120396 0.3048)
			(stroke
				(width 0.1)
				(type default)
			)
			(layer "B.Fab")
		)
		(fp_line
			(start -0.67945 -0.3048)
			(end -0.67945 0.3048)
			(stroke
				(width 0.1)
				(type default)
			)
			(layer "B.Fab")
		)
		(pad "1" smd circle
			(at 0.40005 0)
			(size 0 0)
			(layers "B.Cu" "B.Mask" "B.Paste")
			(net "PVDDCR_CPU0_P1")
		)
		(pad "2" smd circle
			(at -0.40005 0)
			(size 0 0)
			(layers "B.Cu" "B.Mask" "B.Paste")
			(net "GND")
		)
	)
)
